# TIMECARD (Time Appliance Project (Time Card)) — schematic netlist excerpt (pin names and nets, part order shuffled) for the footprints in the layout excerpt that follows; sources: Cadence DE-HDL packaged netlist, KiCad conversion of R4006-B0001-02_R01.brd

C289  CAPACITOR  10UF 6.3V 20%  pkg SMC_0402R_H022  page 9 : \1\ = XP3R3V_PCIE ; \2\ = SG
R293  RESISTOR  4.7KOHM 1%  pkg SMC_0402R_H016  page 25 : \1\ = SG ; \2\ = FPGA_IO_4

(kicad_pcb
	(version 20260206)
	(generator "pcbnew")
	(generator_version "10.0")
	(general
		(thickness 1.6)
		(legacy_teardrops no)
	)
	(paper "A4")
	(title_block
		(title "timecard-production-celestica-r4006 — R4006-B0001-02_R01.brd")
		(comment 1 "Time Appliance Project (Time Card) / footprints 1100-1101 of 1113")
	)
	(layers
		(0 "F.Cu" signal "TOP")
		(4 "In1.Cu" signal "L02_GND1")
		(6 "In2.Cu" signal "L03_SIG1")
		(8 "In3.Cu" signal "L04_GND2")
		(10 "In4.Cu" signal "L05_VCC1")
		(12 "In5.Cu" signal "L06_VCC2")
		(14 "In6.Cu" signal "L07_GND3")
		(16 "In7.Cu" signal "L08_SIG2")
		(18 "In8.Cu" signal "L09_GND4")
		(2 "B.Cu" signal "BOTTOM")
		(9 "F.Adhes" user "F.Adhesive")
		(11 "B.Adhes" user "B.Adhesive")
		(13 "F.Paste" user "Package Geometry/Pastemask Top")
		(15 "B.Paste" user "Package Geometry/Pastemask Bottom")
		(5 "F.SilkS" user "Ref Des/Silkscreen Top")
		(7 "B.SilkS" user "Ref Des/Silkscreen Bottom")
		(1 "F.Mask" user "Board Geometry/Soldermask Top")
		(3 "B.Mask" user "Board Geometry/Soldermask Bottom")
		(17 "Dwgs.User" user "User.Drawings")
		(19 "Cmts.User" user "User.Comments")
		(21 "Eco1.User" user "User.Eco1")
		(23 "Eco2.User" user "User.Eco2")
		(25 "Edge.Cuts" user "Board Geometry/Outline")
		(27 "Margin" user)
		(31 "F.CrtYd" user "Package Geometry/Place Bound Top")
		(29 "B.CrtYd" user "Package Geometry/Place Bound Bottom")
		(35 "F.Fab" user "Ref Des/Assembly Top")
		(33 "B.Fab" user "Ref Des/Assembly Bottom")
	)
	(footprint ""
		(layer "B.Cu")
		(at 54.737 -16.129 -90)
		(property "Reference" "C289"
			(at -4.064 -0.72263 270)
			(unlocked yes)
			(layer "B.SilkS")
			(effects
				(font
					(size 0.7874 0.5842)
					(thickness 0.1524)
				)
				(justify mirror)
			)
		)
		(property "Value" "VAL*"
			(at -0.0762 2.067306 270)
			(unlocked yes)
			(layer "B.Fab")
			(hide yes)
			(effects
				(font
					(size 0.7874 0.5842)
					(thickness 0.1524)
				)
				(justify mirror)
			)
		)
		(property "Device Type" "CAPACITOR-G105-0C106-BM,10UF,2A"
			(at -0.0508 1.127506 270)
			(unlocked yes)
			(layer "B.Fab")
			(hide yes)
			(effects
				(font
					(size 0.7874 0.5842)
					(thickness 0.1524)
				)
				(justify mirror)
			)
		)
		(property "User Part Number" "PARTNUM*"
			(at -0.1016 4.023106 270)
			(unlocked yes)
			(layer "Cmts.User")
			(hide yes)
			(effects
				(font
					(size 0.7874 0.5842)
					(thickness 0.1524)
				)
				(justify mirror)
			)
		)
		(property "Tolerance" "TOL*"
			(at -0.0762 3.032506 270)
			(unlocked yes)
			(layer "Cmts.User")
			(hide yes)
			(effects
				(font
					(size 0.7874 0.5842)
					(thickness 0.1524)
				)
				(justify mirror)
			)
		)
		(duplicate_pad_numbers_are_jumpers no)
		(fp_line
			(start -1.143 0.5588)
			(end -1.143 -0.5588)
			(stroke
				(width 0.1)
				(type default)
			)
			(layer "B.SilkS")
		)
		(fp_line
			(start 1.143 0.5588)
			(end -1.143 0.5588)
			(stroke
				(width 0.1)
				(type default)
			)
			(layer "B.SilkS")
		)
		(fp_line
			(start -1.143 -0.5588)
			(end 1.143 -0.5588)
			(stroke
				(width 0.1)
				(type default)
			)
			(layer "B.SilkS")
		)
		(fp_line
			(start 1.143 -0.5588)
			(end 1.143 0.5588)
			(stroke
				(width 0.1)
				(type default)
			)
			(layer "B.SilkS")
		)
		(fp_poly
			(pts
				(xy 1.143 0.5588) (xy -1.143 0.5588) (xy -1.143 -0.5588) (xy 1.143 -0.5588)
			)
			(stroke
				(width 0)
				(type default)
			)
			(fill no)
			(layer "B.CrtYd")
		)
		(fp_line
			(start -0.508 0.3048)
			(end -0.508 -0.3048)
			(stroke
				(width 0.1)
				(type default)
			)
			(layer "B.Fab")
		)
		(fp_line
			(start 0.508 0.3048)
			(end -0.508 0.3048)
			(stroke
				(width 0.1)
				(type default)
			)
			(layer "B.Fab")
		)
		(fp_line
			(start -0.508 -0.3048)
			(end 0.508 -0.3048)
			(stroke
				(width 0.1)
				(type default)
			)
			(layer "B.Fab")
		)
		(fp_line
			(start 0.508 -0.3048)
			(end 0.508 0.3048)
			(stroke
				(width 0.1)
				(type default)
			)
			(layer "B.Fab")
		)
		(pad "1" smd rect
			(at 0.5334 0 90)
			(size 0.7112 0.6096)
			(layers "B.Cu" "B.Mask" "B.Paste")
			(net "XP3R3V_PCIE")
		)
		(pad "2" smd rect
			(at -0.5334 0 90)
			(size 0.7112 0.6096)
			(layers "B.Cu" "B.Mask" "B.Paste")
			(net "SG")
		)
		(zone
			(layer "B.Cu")
			(hatch none 0.5)
			(connect_pads
				(clearance 0)
			)
			(min_thickness 0.25)
			(keepout
				(tracks not_allowed)
				(vias allowed)
				(pads allowed)
				(copperpour not_allowed)
				(footprints allowed)
			)
			(placement
				(enabled no)
				(sheetname "")
			)
			(fill
				(thermal_gap 0.5)
				(thermal_bridge_width 0.5)
				(island_removal_mode 0)
			)
			(polygon
				(pts
					(xy 54.4322 -16.0528) (xy 55.0418 -16.0528) (xy 55.0418 -16.2052) (xy 54.4322 -16.2052)
				)
			)
		)
		(zone
			(layer "B.Cu")
			(hatch none 0.5)
			(connect_pads
				(clearance 0)
			)
			(min_thickness 0.25)
			(keepout
				(tracks allowed)
				(vias not_allowed)
				(pads allowed)
				(copperpour not_allowed)
				(footprints allowed)
			)
			(placement
				(enabled no)
				(sheetname "")
			)
			(fill
				(thermal_gap 0.5)
				(thermal_bridge_width 0.5)
				(island_removal_mode 0)
			)
			(polygon
				(pts
					(xy 54.4322 -16.0528) (xy 55.0418 -16.0528) (xy 55.0418 -16.2052) (xy 54.4322 -16.2052)
				)
			)
		)
	)
	(footprint ""
		(layer "B.Cu")
		(at 102.5398 -64.2874 90)
		(property "Reference" "R293"
			(at 3.5306 -0.09017 270)
			(unlocked yes)
			(layer "B.SilkS")
			(effects
				(font
					(size 0.7874 0.5842)
					(thickness 0.1524)
				)
				(justify mirror)
			)
		)
		(property "Value" "VAL*"
			(at -0.02032 2.13233 90)
			(unlocked yes)
			(layer "B.Fab")
			(hide yes)
			(effects
				(font
					(size 0.7874 0.5842)
					(thickness 0.1524)
				)
				(justify mirror)
			)
		)
		(property "Tolerance" "TOL*"
			(at -0.044704 3.05435 90)
			(unlocked yes)
			(layer "Cmts.User")
			(hide yes)
			(effects
				(font
					(size 0.7874 0.5842)
					(thickness 0.1524)
				)
				(justify mirror)
			)
		)
		(property "User Part Number" "PARTNUM*"
			(at -0.02032 4.024884 90)
			(unlocked yes)
			(layer "Cmts.User")
			(hide yes)
			(effects
				(font
					(size 0.7874 0.5842)
					(thickness 0.1524)
				)
				(justify mirror)
			)
		)
		(property "Device Type" "RESISTOR-G155-14701-01,4.7KOHMA"
			(at -0.008382 1.210564 90)
			(unlocked yes)
			(layer "B.Fab")
			(hide yes)
			(effects
				(font
					(size 0.7874 0.5842)
					(thickness 0.1524)
				)
				(justify mirror)
			)
		)
		(duplicate_pad_numbers_are_jumpers no)
		(fp_line
			(start 1.143 -0.5588)
			(end 1.143 0.5588)
			(stroke
				(width 0.1)
				(type default)
			)
			(layer "B.SilkS")
		)
		(fp_line
			(start -1.143 -0.5588)
			(end 1.143 -0.5588)
			(stroke
				(width 0.1)
				(type default)
			)
			(layer "B.SilkS")
		)
		(fp_line
			(start 1.143 0.5588)
			(end -1.143 0.5588)
			(stroke
				(width 0.1)
				(type default)
			)
			(layer "B.SilkS")
		)
		(fp_line
			(start -1.143 0.5588)
			(end -1.143 -0.5588)
			(stroke
				(width 0.1)
				(type default)
			)
			(layer "B.SilkS")
		)
		(fp_rect
			(start -1.143 0.5588)
			(end 1.143 -0.5588)
			(stroke
				(width 0)
				(type default)
			)
			(fill no)
			(layer "B.CrtYd")
		)
		(fp_line
			(start 0.508 -0.3048)
			(end 0.508 0.3048)
			(stroke
				(width 0.1)
				(type default)
			)
			(layer "B.Fab")
		)
		(fp_line
			(start -0.508 -0.3048)
			(end 0.508 -0.3048)
			(stroke
				(width 0.1)
				(type default)
			)
			(layer "B.Fab")
		)
		(fp_line
			(start 0.508 0.3048)
			(end -0.508 0.3048)
			(stroke
				(width 0.1)
				(type default)
			)
			(layer "B.Fab")
		)
		(fp_line
			(start -0.508 0.3048)
			(end -0.508 -0.3048)
			(stroke
				(width 0.1)
				(type default)
			)
			(layer "B.Fab")
		)
		(pad "1" smd rect
			(at 0.5334 0 270)
			(size 0.7112 0.6096)
			(layers "B.Cu" "B.Mask" "B.Paste")
			(net "SG")
		)
		(pad "2" smd rect
			(at -0.5334 0 270)
			(size 0.7112 0.6096)
			(layers "B.Cu" "B.Mask" "B.Paste")
			(net "FPGA_IO_4")
		)
		(zone
			(layer "B.Cu")
			(hatch none 0.5)
			(connect_pads
				(clearance 0)
			)
			(min_thickness 0.25)
			(keepout
				(tracks allowed)
				(vias not_allowed)
				(pads allowed)
				(copperpour not_allowed)
				(footprints allowed)
			)
			(placement
				(enabled no)
				(sheetname "")
			)
			(fill
				(thermal_gap 0.5)
				(thermal_bridge_width 0.5)
				(island_removal_mode 0)
			)
			(polygon
				(pts
					(xy 102.8446 -64.2112) (xy 102.8446 -64.3636) (xy 102.235 -64.3636) (xy 102.235 -64.2112)
				)
			)
		)
	)
)
